(kicad_pcb
	(version 20241229)
	(generator "pcbnew")
	(generator_version "9.0")
	(general
		(thickness 1.599998)
		(legacy_teardrops no)
	)
	(paper "A4")
	(title_block
		(date "2023-02-12")
		(rev "1.1.5")
		(comment 9 "footprints 371-377 of 473")
	)
	(layers
		(0 "F.Cu" signal)
		(4 "In1.Cu" power "In1.GND")
		(6 "In2.Cu" signal)
		(8 "In3.Cu" power "In3.GND")
		(10 "In4.Cu" power "In4.VCC")
		(12 "In5.Cu" signal)
		(14 "In6.Cu" power "In6.VCC")
		(2 "B.Cu" signal)
		(9 "F.Adhes" user "F.Adhesive")
		(11 "B.Adhes" user "B.Adhesive")
		(13 "F.Paste" user)
		(15 "B.Paste" user)
		(5 "F.SilkS" user "F.Silkscreen")
		(7 "B.SilkS" user "B.Silkscreen")
		(1 "F.Mask" user)
		(3 "B.Mask" user)
		(17 "Dwgs.User" user "User.Drawings")
		(19 "Cmts.User" user "User.Comments")
		(21 "Eco1.User" user "User.Eco1")
		(23 "Eco2.User" user "User.Eco2")
		(25 "Edge.Cuts" user)
		(27 "Margin" user)
		(31 "F.CrtYd" user "F.Courtyard")
		(29 "B.CrtYd" user "B.Courtyard")
		(35 "F.Fab" user)
		(33 "B.Fab" user)
	)
	(footprint "antmicro-footprints:C_0201"
		(layer "B.Cu")
		(at 167.5 100.625)
		(descr "Capacitor SMD 0201")
		(tags "capacitor SMD 0201")
		(property "Reference" "C78"
			(at 0.85 -0.275 180)
			(layer "B.SilkS")
			(effects
				(font
					(size 0.7 0.7)
					(thickness 0.15)
				)
				(justify left bottom mirror)
			)
		)
		(property "Value" "C_100n_0201"
			(at 0 -1.4 180)
			(layer "B.Fab")
			(effects
				(font
					(size 0.7 0.7)
					(thickness 0.15)
				)
				(justify left bottom mirror)
			)
		)
		(property "Description" " "
			(at 0 0 0)
			(layer "F.Fab")
			(hide yes)
			(effects
				(font
					(size 1.27 1.27)
					(thickness 0.15)
				)
			)
		)
		(property "Author" "Antmicro"
			(at 0 0 0)
			(layer "B.Fab")
			(hide yes)
			(effects
				(font
					(size 1 1)
					(thickness 0.15)
				)
				(justify mirror)
			)
		)
		(property "Dielectric" ""
			(at 0 0 0)
			(layer "B.Fab")
			(hide yes)
			(effects
				(font
					(size 1 1)
					(thickness 0.15)
				)
				(justify mirror)
			)
		)
		(property "License" "Apache-2.0"
			(at 0 0 0)
			(layer "B.Fab")
			(hide yes)
			(effects
				(font
					(size 1 1)
					(thickness 0.15)
				)
				(justify mirror)
			)
		)
		(property "MPN" "CC0201KRX6S5BB104"
			(at 0 0 0)
			(layer "B.Fab")
			(hide yes)
			(effects
				(font
					(size 1 1)
					(thickness 0.15)
				)
				(justify mirror)
			)
		)
		(property "Manufacturer" "Yaego"
			(at 0 0 0)
			(layer "B.Fab")
			(hide yes)
			(effects
				(font
					(size 1 1)
					(thickness 0.15)
				)
				(justify mirror)
			)
		)
		(property "Val" "100n"
			(at 0 0 0)
			(layer "B.Fab")
			(hide yes)
			(effects
				(font
					(size 1 1)
					(thickness 0.15)
				)
				(justify mirror)
			)
		)
		(property "Voltage" ""
			(at 0 0 0)
			(layer "B.Fab")
			(hide yes)
			(effects
				(font
					(size 1 1)
					(thickness 0.15)
				)
				(justify mirror)
			)
		)
		(sheetname "FPGA power")
		(sheetfile "fpga-power.kicad_sch")
		(attr smd)
		(fp_rect
			(start -0.72 0.38)
			(end 0.72 -0.38)
			(stroke
				(width 0.05)
				(type solid)
			)
			(fill no)
			(layer "B.CrtYd")
		)
		(fp_rect
			(start 0.3 -0.15)
			(end -0.301 0.149)
			(stroke
				(width 0.15)
				(type solid)
			)
			(fill no)
			(layer "B.Fab")
		)
		(pad "" smd roundrect
			(at -0.349 0.002)
			(size 0.318 0.36)
			(layers "B.Paste")
			(roundrect_rratio 0.25)
		)
		(pad "" smd roundrect
			(at 0.341 0.002)
			(size 0.318 0.36)
			(layers "B.Paste")
			(roundrect_rratio 0.25)
		)
		(pad "1" smd roundrect
			(at -0.321 0.002)
			(size 0.46 0.4)
			(layers "B.Cu" "B.Mask")
			(roundrect_rratio 0.25)
			(net 465 "1V0_SYS")
			(pintype "passive")
		)
		(pad "2" smd roundrect
			(at 0.32 0.002)
			(size 0.46 0.4)
			(layers "B.Cu" "B.Mask")
			(roundrect_rratio 0.25)
			(net 5 "GND")
			(pintype "passive")
		)
	)
	(footprint "antmicro-footprints:R_0402_1005Metric"
		(layer "B.Cu")
		(at 168.822 115.745757 180)
		(descr "Resistor SMD 0402")
		(tags "resistor SMD 0402")
		(property "Reference" "R53"
			(at -2.978 -0.454243 0)
			(layer "B.SilkS")
			(effects
				(font
					(size 0.7 0.7)
					(thickness 0.15)
				)
				(justify left bottom mirror)
			)
		)
		(property "Value" "R_2k2_0402"
			(at 0 -1.4 0)
			(layer "B.Fab")
			(effects
				(font
					(size 0.7 0.7)
					(thickness 0.15)
				)
				(justify left bottom mirror)
			)
		)
		(property "Description" "2k2 resistor in 0402 package with 1% tolerance"
			(at 0 0 180)
			(layer "F.Fab")
			(hide yes)
			(effects
				(font
					(size 1.27 1.27)
					(thickness 0.15)
				)
			)
		)
		(property "Author" "Antmicro"
			(at 337.644 231.491514 0)
			(layer "B.Fab")
			(hide yes)
			(effects
				(font
					(size 1 1)
					(thickness 0.15)
				)
				(justify mirror)
			)
		)
		(property "License" "Apache-2.0"
			(at 337.644 231.491514 0)
			(layer "B.Fab")
			(hide yes)
			(effects
				(font
					(size 1 1)
					(thickness 0.15)
				)
				(justify mirror)
			)
		)
		(property "MPN" "CR0402-FX-2201GLF"
			(at 337.644 231.491514 0)
			(layer "B.Fab")
			(hide yes)
			(effects
				(font
					(size 1 1)
					(thickness 0.15)
				)
				(justify mirror)
			)
		)
		(property "Manufacturer" "Bourns"
			(at 337.644 231.491514 0)
			(layer "B.Fab")
			(hide yes)
			(effects
				(font
					(size 1 1)
					(thickness 0.15)
				)
				(justify mirror)
			)
		)
		(property "Tolerance" "1%"
			(at 337.644 231.491514 0)
			(layer "B.Fab")
			(hide yes)
			(effects
				(font
					(size 1 1)
					(thickness 0.15)
				)
				(justify mirror)
			)
		)
		(property "Val" "2k2"
			(at 337.644 231.491514 0)
			(layer "B.Fab")
			(hide yes)
			(effects
				(font
					(size 1 1)
					(thickness 0.15)
				)
				(justify mirror)
			)
		)
		(sheetname "Config SPI flash")
		(sheetfile "config-spi.kicad_sch")
		(attr smd)
		(fp_rect
			(start -0.93 0.47)
			(end 0.93 -0.47)
			(stroke
				(width 0.05)
				(type solid)
			)
			(fill no)
			(layer "B.CrtYd")
		)
		(fp_rect
			(start -0.5 0.25)
			(end 0.5 -0.25)
			(stroke
				(width 0.15)
				(type solid)
			)
			(fill no)
			(layer "B.Fab")
		)
		(pad "1" smd roundrect
			(at -0.485 0 180)
			(size 0.59 0.64)
			(layers "B.Cu" "B.Mask" "B.Paste")
			(roundrect_rratio 0.25)
			(net 459 "3V3_SYS")
			(pintype "passive")
		)
		(pad "2" smd roundrect
			(at 0.485 0 180)
			(size 0.59 0.64)
			(layers "B.Cu" "B.Mask" "B.Paste")
			(roundrect_rratio 0.25)
			(net 212 "FCS_B")
			(pintype "passive")
		)
	)
	(footprint "antmicro-footprints:C_0402_1005Metric"
		(layer "B.Cu")
		(at 174.5 92 90)
		(descr "Capacitor SMD 0402")
		(tags "capacitor SMD 0402")
		(property "Reference" "C28"
			(at 3.6 1 270)
			(layer "B.SilkS")
			(effects
				(font
					(size 0.7 0.7)
					(thickness 0.15)
				)
				(justify left bottom mirror)
			)
		)
		(property "Value" "C_4u7_0402"
			(at 0 -1.4 270)
			(layer "B.Fab")
			(effects
				(font
					(size 0.7 0.7)
					(thickness 0.15)
				)
				(justify left bottom mirror)
			)
		)
		(property "Description" " "
			(at 0 0 90)
			(layer "F.Fab")
			(hide yes)
			(effects
				(font
					(size 1.27 1.27)
					(thickness 0.15)
				)
			)
		)
		(property "Author" "Antmicro"
			(at 266.5 -82.5 0)
			(layer "B.Fab")
			(hide yes)
			(effects
				(font
					(size 1 1)
					(thickness 0.15)
				)
				(justify mirror)
			)
		)
		(property "Dielectric" ""
			(at 266.5 -82.5 0)
			(layer "B.Fab")
			(hide yes)
			(effects
				(font
					(size 1 1)
					(thickness 0.15)
				)
				(justify mirror)
			)
		)
		(property "License" "Apache-2.0"
			(at 266.5 -82.5 0)
			(layer "B.Fab")
			(hide yes)
			(effects
				(font
					(size 1 1)
					(thickness 0.15)
				)
				(justify mirror)
			)
		)
		(property "MPN" "GRM155R61A475MEAAD"
			(at 266.5 -82.5 0)
			(layer "B.Fab")
			(hide yes)
			(effects
				(font
					(size 1 1)
					(thickness 0.15)
				)
				(justify mirror)
			)
		)
		(property "Manufacturer" "Murata"
			(at 266.5 -82.5 0)
			(layer "B.Fab")
			(hide yes)
			(effects
				(font
					(size 1 1)
					(thickness 0.15)
				)
				(justify mirror)
			)
		)
		(property "Val" "4u7"
			(at 266.5 -82.5 0)
			(layer "B.Fab")
			(hide yes)
			(effects
				(font
					(size 1 1)
					(thickness 0.15)
				)
				(justify mirror)
			)
		)
		(property "Voltage" ""
			(at 266.5 -82.5 0)
			(layer "B.Fab")
			(hide yes)
			(effects
				(font
					(size 1 1)
					(thickness 0.15)
				)
				(justify mirror)
			)
		)
		(sheetname "FPGA power")
		(sheetfile "fpga-power.kicad_sch")
		(attr smd)
		(fp_rect
			(start -0.94 0.47)
			(end 0.94 -0.47)
			(stroke
				(width 0.05)
				(type solid)
			)
			(fill no)
			(layer "B.CrtYd")
		)
		(fp_rect
			(start -0.499 0.249)
			(end 0.499 -0.249)
			(stroke
				(width 0.15)
				(type solid)
			)
			(fill no)
			(layer "B.Fab")
		)
		(pad "1" smd roundrect
			(at -0.484 0 90)
			(size 0.59 0.64)
			(layers "B.Cu" "B.Mask" "B.Paste")
			(roundrect_rratio 0.25)
			(net 459 "3V3_SYS")
			(pintype "passive")
		)
		(pad "2" smd roundrect
			(at 0.484 0 90)
			(size 0.59 0.64)
			(layers "B.Cu" "B.Mask" "B.Paste")
			(roundrect_rratio 0.25)
			(net 5 "GND")
			(pintype "passive")
		)
	)
	(footprint "antmicro-footprints:C_0402_1005Metric"
		(layer "B.Cu")
		(at 176 91.5 180)
		(descr "Capacitor SMD 0402")
		(tags "capacitor SMD 0402")
		(property "Reference" "C32"
			(at -2.9 -0.4 0)
			(layer "B.SilkS")
			(effects
				(font
					(size 0.7 0.7)
					(thickness 0.15)
				)
				(justify left bottom mirror)
			)
		)
		(property "Value" "C_4u7_0402"
			(at 0 -1.4 0)
			(layer "B.Fab")
			(effects
				(font
					(size 0.7 0.7)
					(thickness 0.15)
				)
				(justify left bottom mirror)
			)
		)
		(property "Description" " "
			(at 0 0 180)
			(layer "F.Fab")
			(hide yes)
			(effects
				(font
					(size 1.27 1.27)
					(thickness 0.15)
				)
			)
		)
		(property "Author" "Antmicro"
			(at 352 183 0)
			(layer "B.Fab")
			(hide yes)
			(effects
				(font
					(size 1 1)
					(thickness 0.15)
				)
				(justify mirror)
			)
		)
		(property "Dielectric" ""
			(at 352 183 0)
			(layer "B.Fab")
			(hide yes)
			(effects
				(font
					(size 1 1)
					(thickness 0.15)
				)
				(justify mirror)
			)
		)
		(property "License" "Apache-2.0"
			(at 352 183 0)
			(layer "B.Fab")
			(hide yes)
			(effects
				(font
					(size 1 1)
					(thickness 0.15)
				)
				(justify mirror)
			)
		)
		(property "MPN" "GRM155R61A475MEAAD"
			(at 352 183 0)
			(layer "B.Fab")
			(hide yes)
			(effects
				(font
					(size 1 1)
					(thickness 0.15)
				)
				(justify mirror)
			)
		)
		(property "Manufacturer" "Murata"
			(at 352 183 0)
			(layer "B.Fab")
			(hide yes)
			(effects
				(font
					(size 1 1)
					(thickness 0.15)
				)
				(justify mirror)
			)
		)
		(property "Val" "4u7"
			(at 352 183 0)
			(layer "B.Fab")
			(hide yes)
			(effects
				(font
					(size 1 1)
					(thickness 0.15)
				)
				(justify mirror)
			)
		)
		(property "Voltage" ""
			(at 352 183 0)
			(layer "B.Fab")
			(hide yes)
			(effects
				(font
					(size 1 1)
					(thickness 0.15)
				)
				(justify mirror)
			)
		)
		(sheetname "FPGA power")
		(sheetfile "fpga-power.kicad_sch")
		(attr smd)
		(fp_rect
			(start -0.94 0.47)
			(end 0.94 -0.47)
			(stroke
				(width 0.05)
				(type solid)
			)
			(fill no)
			(layer "B.CrtYd")
		)
		(fp_rect
			(start -0.499 0.249)
			(end 0.499 -0.249)
			(stroke
				(width 0.15)
				(type solid)
			)
			(fill no)
			(layer "B.Fab")
		)
		(pad "1" smd roundrect
			(at -0.484 0 180)
			(size 0.59 0.64)
			(layers "B.Cu" "B.Mask" "B.Paste")
			(roundrect_rratio 0.25)
			(net 459 "3V3_SYS")
			(pintype "passive")
		)
		(pad "2" smd roundrect
			(at 0.484 0 180)
			(size 0.59 0.64)
			(layers "B.Cu" "B.Mask" "B.Paste")
			(roundrect_rratio 0.25)
			(net 5 "GND")
			(pintype "passive")
		)
	)
	(footprint "antmicro-footprints:C_0402_1005Metric"
		(layer "B.Cu")
		(at 176.875 94.75 180)
		(descr "Capacitor SMD 0402")
		(tags "capacitor SMD 0402")
		(property "Reference" "C36"
			(at -1.125 0.45 0)
			(layer "B.SilkS")
			(effects
				(font
					(size 0.7 0.7)
					(thickness 0.15)
				)
				(justify left bottom mirror)
			)
		)
		(property "Value" "C_4u7_0402"
			(at 0 -1.4 0)
			(layer "B.Fab")
			(effects
				(font
					(size 0.7 0.7)
					(thickness 0.15)
				)
				(justify left bottom mirror)
			)
		)
		(property "Description" " "
			(at 0 0 180)
			(layer "F.Fab")
			(hide yes)
			(effects
				(font
					(size 1.27 1.27)
					(thickness 0.15)
				)
			)
		)
		(property "Author" "Antmicro"
			(at 353.75 189.5 0)
			(layer "B.Fab")
			(hide yes)
			(effects
				(font
					(size 1 1)
					(thickness 0.15)
				)
				(justify mirror)
			)
		)
		(property "Dielectric" ""
			(at 353.75 189.5 0)
			(layer "B.Fab")
			(hide yes)
			(effects
				(font
					(size 1 1)
					(thickness 0.15)
				)
				(justify mirror)
			)
		)
		(property "License" "Apache-2.0"
			(at 353.75 189.5 0)
			(layer "B.Fab")
			(hide yes)
			(effects
				(font
					(size 1 1)
					(thickness 0.15)
				)
				(justify mirror)
			)
		)
		(property "MPN" "GRM155R61A475MEAAD"
			(at 353.75 189.5 0)
			(layer "B.Fab")
			(hide yes)
			(effects
				(font
					(size 1 1)
					(thickness 0.15)
				)
				(justify mirror)
			)
		)
		(property "Manufacturer" "Murata"
			(at 353.75 189.5 0)
			(layer "B.Fab")
			(hide yes)
			(effects
				(font
					(size 1 1)
					(thickness 0.15)
				)
				(justify mirror)
			)
		)
		(property "Val" "4u7"
			(at 353.75 189.5 0)
			(layer "B.Fab")
			(hide yes)
			(effects
				(font
					(size 1 1)
					(thickness 0.15)
				)
				(justify mirror)
			)
		)
		(property "Voltage" ""
			(at 353.75 189.5 0)
			(layer "B.Fab")
			(hide yes)
			(effects
				(font
					(size 1 1)
					(thickness 0.15)
				)
				(justify mirror)
			)
		)
		(sheetname "FPGA power")
		(sheetfile "fpga-power.kicad_sch")
		(attr smd)
		(fp_rect
			(start -0.94 0.47)
			(end 0.94 -0.47)
			(stroke
				(width 0.05)
				(type solid)
			)
			(fill no)
			(layer "B.CrtYd")
		)
		(fp_rect
			(start -0.499 0.249)
			(end 0.499 -0.249)
			(stroke
				(width 0.15)
				(type solid)
			)
			(fill no)
			(layer "B.Fab")
		)
		(pad "1" smd roundrect
			(at -0.484 0 180)
			(size 0.59 0.64)
			(layers "B.Cu" "B.Mask" "B.Paste")
			(roundrect_rratio 0.25)
			(net 459 "3V3_SYS")
			(pintype "passive")
		)
		(pad "2" smd roundrect
			(at 0.484 0 180)
			(size 0.59 0.64)
			(layers "B.Cu" "B.Mask" "B.Paste")
			(roundrect_rratio 0.25)
			(net 5 "GND")
			(pintype "passive")
		)
	)
	(footprint "antmicro-footprints:C_0402_1005Metric"
		(layer "B.Cu")
		(at 177.5 99.125 180)
		(descr "Capacitor SMD 0402")
		(tags "capacitor SMD 0402")
		(property "Reference" "C40"
			(at -1.1 -1.275 0)
			(layer "B.SilkS")
			(effects
				(font
					(size 0.7 0.7)
					(thickness 0.15)
				)
				(justify left bottom mirror)
			)
		)
		(property "Value" "C_4u7_0402"
			(at 0 -1.4 0)
			(layer "B.Fab")
			(effects
				(font
					(size 0.7 0.7)
					(thickness 0.15)
				)
				(justify left bottom mirror)
			)
		)
		(property "Description" " "
			(at 0 0 180)
			(layer "F.Fab")
			(hide yes)
			(effects
				(font
					(size 1.27 1.27)
					(thickness 0.15)
				)
			)
		)
		(property "Author" "Antmicro"
			(at 355 198.25 0)
			(layer "B.Fab")
			(hide yes)
			(effects
				(font
					(size 1 1)
					(thickness 0.15)
				)
				(justify mirror)
			)
		)
		(property "Dielectric" ""
			(at 355 198.25 0)
			(layer "B.Fab")
			(hide yes)
			(effects
				(font
					(size 1 1)
					(thickness 0.15)
				)
				(justify mirror)
			)
		)
		(property "License" "Apache-2.0"
			(at 355 198.25 0)
			(layer "B.Fab")
			(hide yes)
			(effects
				(font
					(size 1 1)
					(thickness 0.15)
				)
				(justify mirror)
			)
		)
		(property "MPN" "GRM155R61A475MEAAD"
			(at 355 198.25 0)
			(layer "B.Fab")
			(hide yes)
			(effects
				(font
					(size 1 1)
					(thickness 0.15)
				)
				(justify mirror)
			)
		)
		(property "Manufacturer" "Murata"
			(at 355 198.25 0)
			(layer "B.Fab")
			(hide yes)
			(effects
				(font
					(size 1 1)
					(thickness 0.15)
				)
				(justify mirror)
			)
		)
		(property "Val" "4u7"
			(at 355 198.25 0)
			(layer "B.Fab")
			(hide yes)
			(effects
				(font
					(size 1 1)
					(thickness 0.15)
				)
				(justify mirror)
			)
		)
		(property "Voltage" ""
			(at 355 198.25 0)
			(layer "B.Fab")
			(hide yes)
			(effects
				(font
					(size 1 1)
					(thickness 0.15)
				)
				(justify mirror)
			)
		)
		(sheetname "FPGA power")
		(sheetfile "fpga-power.kicad_sch")
		(attr smd)
		(fp_rect
			(start -0.94 0.47)
			(end 0.94 -0.47)
			(stroke
				(width 0.05)
				(type solid)
			)
			(fill no)
			(layer "B.CrtYd")
		)
		(fp_rect
			(start -0.499 0.249)
			(end 0.499 -0.249)
			(stroke
				(width 0.15)
				(type solid)
			)
			(fill no)
			(layer "B.Fab")
		)
		(pad "1" smd roundrect
			(at -0.484 0 180)
			(size 0.59 0.64)
			(layers "B.Cu" "B.Mask" "B.Paste")
			(roundrect_rratio 0.25)
			(net 459 "3V3_SYS")
			(pintype "passive")
		)
		(pad "2" smd roundrect
			(at 0.484 0 180)
			(size 0.59 0.64)
			(layers "B.Cu" "B.Mask" "B.Paste")
			(roundrect_rratio 0.25)
			(net 5 "GND")
			(pintype "passive")
		)
	)
	(footprint "antmicro-footprints:C_0402_1005Metric"
		(layer "B.Cu")
		(at 177.036328 101.997157 90)
		(descr "Capacitor SMD 0402")
		(tags "capacitor SMD 0402")
		(property "Reference" "C46"
			(at 1.097157 1.263672 270)
			(layer "B.SilkS")
			(effects
				(font
					(size 0.7 0.7)
					(thickness 0.15)
				)
				(justify left bottom mirror)
			)
		)
		(property "Value" "C_4u7_0402"
			(at 0 -1.4 270)
			(layer "B.Fab")
			(effects
				(font
					(size 0.7 0.7)
					(thickness 0.15)
				)
				(justify left bottom mirror)
			)
		)
		(property "Description" " "
			(at 0 0 90)
			(layer "F.Fab")
			(hide yes)
			(effects
				(font
					(size 1.27 1.27)
					(thickness 0.15)
				)
			)
		)
		(property "Author" "Antmicro"
			(at 279.033485 -75.039171 0)
			(layer "B.Fab")
			(hide yes)
			(effects
				(font
					(size 1 1)
					(thickness 0.15)
				)
				(justify mirror)
			)
		)
		(property "Dielectric" ""
			(at 279.033485 -75.039171 0)
			(layer "B.Fab")
			(hide yes)
			(effects
				(font
					(size 1 1)
					(thickness 0.15)
				)
				(justify mirror)
			)
		)
		(property "License" "Apache-2.0"
			(at 279.033485 -75.039171 0)
			(layer "B.Fab")
			(hide yes)
			(effects
				(font
					(size 1 1)
					(thickness 0.15)
				)
				(justify mirror)
			)
		)
		(property "MPN" "GRM155R61A475MEAAD"
			(at 279.033485 -75.039171 0)
			(layer "B.Fab")
			(hide yes)
			(effects
				(font
					(size 1 1)
					(thickness 0.15)
				)
				(justify mirror)
			)
		)
		(property "Manufacturer" "Murata"
			(at 279.033485 -75.039171 0)
			(layer "B.Fab")
			(hide yes)
			(effects
				(font
					(size 1 1)
					(thickness 0.15)
				)
				(justify mirror)
			)
		)
		(property "Val" "4u7"
			(at 279.033485 -75.039171 0)
			(layer "B.Fab")
			(hide yes)
			(effects
				(font
					(size 1 1)
					(thickness 0.15)
				)
				(justify mirror)
			)
		)
		(property "Voltage" ""
			(at 279.033485 -75.039171 0)
			(layer "B.Fab")
			(hide yes)
			(effects
				(font
					(size 1 1)
					(thickness 0.15)
				)
				(justify mirror)
			)
		)
		(sheetname "FPGA power")
		(sheetfile "fpga-power.kicad_sch")
		(attr smd)
		(fp_rect
			(start -0.94 0.47)
			(end 0.94 -0.47)
			(stroke
				(width 0.05)
				(type solid)
			)
			(fill no)
			(layer "B.CrtYd")
		)
		(fp_rect
			(start -0.499 0.249)
			(end 0.499 -0.249)
			(stroke
				(width 0.15)
				(type solid)
			)
			(fill no)
			(layer "B.Fab")
		)
		(pad "1" smd roundrect
			(at -0.484 0 90)
			(size 0.59 0.64)
			(layers "B.Cu" "B.Mask" "B.Paste")
			(roundrect_rratio 0.25)
			(net 459 "3V3_SYS")
			(pintype "passive")
		)
		(pad "2" smd roundrect
			(at 0.484 0 90)
			(size 0.59 0.64)
			(layers "B.Cu" "B.Mask" "B.Paste")
			(roundrect_rratio 0.25)
			(net 5 "GND")
			(pintype "passive")
		)
	)
)
